# BASEBOARD_FAB2 (Tioga Pass) — schematic netlist excerpt (pin names and nets, part order shuffled) for the footprints in the layout excerpt that follows; sources: Cadence DE-HDL packaged netlist, KiCad conversion of Wiwynn_Tioga_Pass_MB.brd

C3M37  CAP  0.22UF 16V 10% X7R  pkg 0402  page 129 : A = DMI_CPU0_PCH_RX_DP<1> ; B = DMI_CPU0_PCH_RX_C_DP<1>
C3P45  CAP  0.047UF 25V 10% X7R  pkg 0402  page 196 : A = A_ADM1085_CEXT ; B = GND
R7D38  RES  0.0 5% EMPTY  pkg 0402  page 104 : A = FM_CPU1_VRM_OSC_EN ; B = FM_CPU1_STL_BRD_OSC_EN

(kicad_pcb
	(version 20260206)
	(generator "pcbnew")
	(generator_version "10.0")
	(general
		(thickness 1.6)
		(legacy_teardrops no)
	)
	(paper "A4")
	(title_block
		(title "Wiwynn_Tioga_Pass_MB.brd")
		(comment 1 "Tioga Pass / footprints 4631-4633 of 4770")
	)
	(layers
		(0 "F.Cu" signal "TOP")
		(4 "In1.Cu" signal "L2GND")
		(6 "In2.Cu" signal "L3")
		(8 "In3.Cu" signal "L4GND")
		(10 "In4.Cu" signal "L5")
		(12 "In5.Cu" signal "L6GND")
		(14 "In6.Cu" signal "L7VCC")
		(16 "In7.Cu" signal "L8VCC")
		(18 "In8.Cu" signal "L9GND")
		(20 "In9.Cu" signal "L10")
		(22 "In10.Cu" signal "L11GND")
		(24 "In11.Cu" signal "L12")
		(26 "In12.Cu" signal "L13GND")
		(2 "B.Cu" signal "BOTTOM")
		(9 "F.Adhes" user "F.Adhesive")
		(11 "B.Adhes" user "B.Adhesive")
		(13 "F.Paste" user "Package Geometry/Pastemask Top")
		(15 "B.Paste" user "Package Geometry/Pastemask Bottom")
		(5 "F.SilkS" user "Ref Des/Silkscreen Top")
		(7 "B.SilkS" user "Ref Des/Silkscreen Bottom")
		(1 "F.Mask" user "Board Geometry/Soldermask Top")
		(3 "B.Mask" user "Board Geometry/Soldermask Bottom")
		(17 "Dwgs.User" user "User.Drawings")
		(19 "Cmts.User" user "User.Comments")
		(21 "Eco1.User" user "User.Eco1")
		(23 "Eco2.User" user "User.Eco2")
		(25 "Edge.Cuts" user "Board Geometry/Outline")
		(27 "Margin" user)
		(31 "F.CrtYd" user "Package Geometry/Place Bound Top")
		(29 "B.CrtYd" user "Package Geometry/Place Bound Bottom")
		(35 "F.Fab" user "Ref Des/Assembly Top")
		(33 "B.Fab" user "Ref Des/Assembly Bottom")
	)
	(footprint ""
		(layer "B.Cu")
		(at 365.506 -78.3336 -90)
		(property "Reference" "R7D38"
			(at 0 0 90)
			(layer "B.SilkS")
			(hide yes)
			(effects
				(font
					(size 1.27 1.27)
				)
				(justify mirror)
			)
		)
		(property "Value" ""
			(at 0 0 90)
			(layer "B.Fab")
			(effects
				(font
					(size 1.27 1.27)
				)
				(justify mirror)
			)
		)
		(duplicate_pad_numbers_are_jumpers no)
		(fp_poly
			(pts
				(xy 0.2794 -0.1016) (xy -0.2794 -0.1016) (xy -0.2794 0.9906) (xy 0.2794 0.9906)
			)
			(stroke
				(width 0)
				(type default)
			)
			(fill no)
			(layer "B.CrtYd")
		)
		(fp_line
			(start -0.2794 0.9906)
			(end -0.2794 -0.1016)
			(stroke
				(width 0.1)
				(type default)
			)
			(layer "B.Fab")
		)
		(fp_line
			(start 0.2794 0.9906)
			(end -0.2794 0.9906)
			(stroke
				(width 0.1)
				(type default)
			)
			(layer "B.Fab")
		)
		(fp_line
			(start -0.2794 -0.1016)
			(end 0.2794 -0.1016)
			(stroke
				(width 0.1)
				(type default)
			)
			(layer "B.Fab")
		)
		(fp_line
			(start 0.2794 -0.1016)
			(end 0.2794 0.9906)
			(stroke
				(width 0.1)
				(type default)
			)
			(layer "B.Fab")
		)
		(pad "1" smd rect
			(at 0 0 90)
			(size 0.508 0.508)
			(layers "B.Cu" "B.Mask" "B.Paste")
			(net "FM_CPU1_VRM_OSC_EN")
		)
		(pad "2" smd rect
			(at 0 0.889 90)
			(size 0.508 0.508)
			(layers "B.Cu" "B.Mask" "B.Paste")
			(net "FM_CPU1_STL_BRD_OSC_EN")
		)
		(zone
			(layer "B.Cu")
			(hatch none 0.5)
			(connect_pads
				(clearance 0)
			)
			(min_thickness 0.25)
			(keepout
				(tracks not_allowed)
				(vias allowed)
				(pads allowed)
				(copperpour not_allowed)
				(footprints allowed)
			)
			(placement
				(enabled no)
				(sheetname "")
			)
			(fill
				(thermal_gap 0.5)
				(thermal_bridge_width 0.5)
				(island_removal_mode 0)
			)
			(polygon
				(pts
					(xy 364.871 -78.0796) (xy 364.871 -78.5876) (xy 365.252 -78.5876) (xy 365.252 -78.0796)
				)
			)
		)
		(zone
			(layer "B.Cu")
			(hatch none 0.5)
			(connect_pads
				(clearance 0)
			)
			(min_thickness 0.25)
			(keepout
				(tracks allowed)
				(vias not_allowed)
				(pads allowed)
				(copperpour not_allowed)
				(footprints allowed)
			)
			(placement
				(enabled no)
				(sheetname "")
			)
			(fill
				(thermal_gap 0.5)
				(thermal_bridge_width 0.5)
				(island_removal_mode 0)
			)
			(polygon
				(pts
					(xy 365.252 -78.0796) (xy 365.252 -78.5876) (xy 364.871 -78.5876) (xy 364.871 -78.0796)
				)
			)
		)
	)
	(footprint ""
		(layer "B.Cu")
		(at 422.91 -7.5565)
		(property "Reference" "C3P45"
			(at 0 0 0)
			(layer "B.SilkS")
			(hide yes)
			(effects
				(font
					(size 1.27 1.27)
				)
				(justify mirror)
			)
		)
		(property "Value" ""
			(at 0 0 0)
			(layer "B.Fab")
			(effects
				(font
					(size 1.27 1.27)
				)
				(justify mirror)
			)
		)
		(duplicate_pad_numbers_are_jumpers no)
		(fp_rect
			(start -0.3048 0.9906)
			(end 0.3048 -0.1016)
			(stroke
				(width 0)
				(type default)
			)
			(fill no)
			(layer "B.CrtYd")
		)
		(fp_line
			(start -0.3048 -0.1016)
			(end 0.3048 -0.1016)
			(stroke
				(width 0.1)
				(type default)
			)
			(layer "B.Fab")
		)
		(fp_line
			(start -0.3048 0.9906)
			(end -0.3048 -0.1016)
			(stroke
				(width 0.1)
				(type default)
			)
			(layer "B.Fab")
		)
		(fp_line
			(start 0.3048 -0.1016)
			(end 0.3048 0.9906)
			(stroke
				(width 0.1)
				(type default)
			)
			(layer "B.Fab")
		)
		(fp_line
			(start 0.3048 0.9906)
			(end -0.3048 0.9906)
			(stroke
				(width 0.1)
				(type default)
			)
			(layer "B.Fab")
		)
		(pad "1" smd rect
			(at 0 0 180)
			(size 0.508 0.508)
			(layers "B.Cu" "B.Mask" "B.Paste")
			(net "A_ADM1085_CEXT")
		)
		(pad "2" smd rect
			(at 0 0.889 180)
			(size 0.508 0.508)
			(layers "B.Cu" "B.Mask" "B.Paste")
			(net "GND")
		)
		(zone
			(layer "B.Cu")
			(hatch none 0.5)
			(connect_pads
				(clearance 0)
			)
			(min_thickness 0.25)
			(keepout
				(tracks allowed)
				(vias not_allowed)
				(pads allowed)
				(copperpour not_allowed)
				(footprints allowed)
			)
			(placement
				(enabled no)
				(sheetname "")
			)
			(fill
				(thermal_gap 0.5)
				(thermal_bridge_width 0.5)
				(island_removal_mode 0)
			)
			(polygon
				(pts
					(xy 422.656 -6.9215) (xy 423.164 -6.9215) (xy 423.164 -7.3025) (xy 422.656 -7.3025)
				)
			)
		)
		(zone
			(layer "B.Cu")
			(hatch none 0.5)
			(connect_pads
				(clearance 0)
			)
			(min_thickness 0.25)
			(keepout
				(tracks not_allowed)
				(vias allowed)
				(pads allowed)
				(copperpour not_allowed)
				(footprints allowed)
			)
			(placement
				(enabled no)
				(sheetname "")
			)
			(fill
				(thermal_gap 0.5)
				(thermal_bridge_width 0.5)
				(island_removal_mode 0)
			)
			(polygon
				(pts
					(xy 422.656 -6.9215) (xy 423.164 -6.9215) (xy 423.164 -7.3025) (xy 422.656 -7.3025)
				)
			)
		)
	)
	(footprint ""
		(layer "B.Cu")
		(at 365.506 -115.189 -90)
		(property "Reference" "C3M37"
			(at 0 0 90)
			(layer "B.SilkS")
			(hide yes)
			(effects
				(font
					(size 1.27 1.27)
				)
				(justify mirror)
			)
		)
		(property "Value" ""
			(at 0 0 90)
			(layer "B.Fab")
			(effects
				(font
					(size 1.27 1.27)
				)
				(justify mirror)
			)
		)
		(duplicate_pad_numbers_are_jumpers no)
		(fp_poly
			(pts
				(xy -0.3048 -0.1016) (xy -0.3048 0.9906) (xy 0.3048 0.9906) (xy 0.3048 -0.1016)
			)
			(stroke
				(width 0)
				(type default)
			)
			(fill no)
			(layer "B.CrtYd")
		)
		(fp_line
			(start -0.3048 0.9906)
			(end -0.3048 -0.1016)
			(stroke
				(width 0.1)
				(type default)
			)
			(layer "B.Fab")
		)
		(fp_line
			(start 0.3048 0.9906)
			(end -0.3048 0.9906)
			(stroke
				(width 0.1)
				(type default)
			)
			(layer "B.Fab")
		)
		(fp_line
			(start -0.3048 -0.1016)
			(end 0.3048 -0.1016)
			(stroke
				(width 0.1)
				(type default)
			)
			(layer "B.Fab")
		)
		(fp_line
			(start 0.3048 -0.1016)
			(end 0.3048 0.9906)
			(stroke
				(width 0.1)
				(type default)
			)
			(layer "B.Fab")
		)
		(pad "1" smd rect
			(at 0 0 90)
			(size 0.508 0.508)
			(layers "B.Cu" "B.Mask" "B.Paste")
			(net "DMI_CPU0_PCH_RX_DP<1>")
		)
		(pad "2" smd rect
			(at 0 0.889 90)
			(size 0.508 0.508)
			(layers "B.Cu" "B.Mask" "B.Paste")
			(net "DMI_CPU0_PCH_RX_C_DP<1>")
		)
		(zone
			(layer "B.Cu")
			(hatch none 0.5)
			(connect_pads
				(clearance 0)
			)
			(min_thickness 0.25)
			(keepout
				(tracks not_allowed)
				(vias allowed)
				(pads allowed)
				(copperpour not_allowed)
				(footprints allowed)
			)
			(placement
				(enabled no)
				(sheetname "")
			)
			(fill
				(thermal_gap 0.5)
				(thermal_bridge_width 0.5)
				(island_removal_mode 0)
			)
			(polygon
				(pts
					(xy 364.871 -114.935) (xy 364.871 -115.443) (xy 365.252 -115.443) (xy 365.252 -114.935)
				)
			)
		)
		(zone
			(layer "B.Cu")
			(hatch none 0.5)
			(connect_pads
				(clearance 0)
			)
			(min_thickness 0.25)
			(keepout
				(tracks allowed)
				(vias not_allowed)
				(pads allowed)
				(copperpour not_allowed)
				(footprints allowed)
			)
			(placement
				(enabled no)
				(sheetname "")
			)
			(fill
				(thermal_gap 0.5)
				(thermal_bridge_width 0.5)
				(island_removal_mode 0)
			)
			(polygon
				(pts
					(xy 365.252 -114.935) (xy 365.252 -115.443) (xy 364.871 -115.443) (xy 364.871 -114.935)
				)
			)
		)
	)
)
